#ISCELL
  mstr_symbols design_note *
  *
#ISCELL
  mstr_symbols intel_corp_bpage *
  *
#ISCELL
  mstr_symbols vcc_core *
  page193_i107
#ISCELL
  mstr_standard offpage *
  page193_i111
#ISCELL
  mstr_standard offpage *
  page193_i112
#ISCELL
  mstr_standard offpage *
  page193_i113
#ISCELL
  mstr_standard offpage *
  page193_i114
#ISCELL
  mstr_symbols vcc_core *
  page193_i131
#ISCELL
  mstr_symbols vcc_core *
  page193_i134
#ISCELL
  mstr_standard offpage *
  page193_i138
#CELL
  dev_discrete cap_a *
  page193_i140
#CELL
  dev_discrete cap_a *
  page193_i141
#ISCELL
  mstr_symbols pvccio_cpu1 *
  page193_i144
#ISCELL
  mstr_standard offpage *
  page193_i149
#ISCELL
  mstr_standard offpage *
  page193_i150
#ISCELL
  mstr_standard offpage *
  page193_i151
#ISCELL
  mstr_standard offpage *
  page193_i152
#ISCELL
  mstr_standard offpage *
  page193_i153
#ISCELL
  mstr_standard offpage *
  page193_i154
#ISCELL
  mstr_standard offpage *
  page193_i155
#ISCELL
  mstr_standard offpage *
  page193_i156
#ISCELL
  mstr_standard offpage *
  page193_i157
#ISCELL
  mstr_symbols vcc_core *
  page193_i161
#ISCELL
  mstr_symbols vcc_core *
  page193_i162
#ISCELL
  mstr_symbols vcc_core *
  page193_i164
#ISCELL
  mstr_symbols vcc_core *
  page193_i165
#ISCELL
  mstr_symbols vcc_core *
  page193_i166
#ISCELL
  mstr_symbols vcc_core *
  page193_i167
#ISCELL
  mstr_symbols vcc_core *
  page193_i168
#CELL
  mstr_discrete res *
  page193_i169
#CELL
  mstr_discrete res *
  page193_i170
#ISCELL
  mstr_symbols gnd *
  page193_i171
#ISCELL
  mstr_symbols p3v3 *
  page193_i173
#ISCELL
  mstr_standard offpage *
  page193_i174
#CELL
  mstr_discrete capp *
  page193_i175
#ISCELL
  mstr_standard offpage *
  page193_i2
#CELL
  mstr_discrete capp *
  page193_i29
#ISCELL
  mstr_symbols gnd *
  page193_i30
#CELL
  dev_discrete cap_a *
  page193_i31
#ISCELL
  mstr_symbols gnd *
  page193_i37
#CELL
  dev_discrete cap_a *
  page193_i38
#ISCELL
  mstr_standard offpage *
  page193_i4
#CELL
  mstr_sconn sconn120_h61426002 *
  page193_i45
#CELL
  mstr_sconn sconn120_h61426002 *
  page193_i46
#ISCELL
  mstr_standard offpage *
  page193_i49
#ISCELL
  mstr_standard offpage *
  page193_i5
#ISCELL
  mstr_standard offpage *
  page193_i50
#ISCELL
  mstr_symbols gnd *
  page193_i56
#ISCELL
  mstr_symbols gnd *
  page193_i60
#CELL
  mstr_discrete capp *
  page193_i61
#CELL
  mstr_discrete capp *
  page193_i62
#ISCELL
  mstr_symbols gnd *
  page193_i64
#CELL
  dev_discrete cap_a *
  page193_i68
#CELL
  dev_discrete cap_a *
  page193_i70
#ISCELL
  mstr_symbols gnd *
  page193_i75
#ISCELL
  mstr_symbols gnd *
  page193_i81
#ISCELL
  mstr_standard offpage *
  page193_i83
#ISCELL
  mstr_standard offpage *
  page193_i84
#ISCELL
  mstr_symbols gnd *
  page193_i85
#ISCELL
  mstr_symbols p12v_stby *
  page193_i86
#ISCELL
  mstr_symbols p3v3_stby *
  page193_i87
#ISCELL
  mstr_symbols p5v_stby *
  page193_i88
#ISCELL
  mstr_standard offpage *
  page193_i90
#ISCELL
  mstr_symbols gnd *
  page193_i94
#ISCELL
  mstr_symbols gnd *
  page193_i95
